(kicad_pcb
	(version 20221018)
	(generator pcbnew)
	(general
    (thickness 1.518)
  )
	(paper "A4")
	(title_block
    (title "Kria K26 Devboard")
    (date "2024-03-26")
    (rev "1.2.5")
    (comment 1 "www.antmicro.com")
    (comment 2 "Antmicro Ltd.")
		(comment 9 "footprints 1-10 of 660")
	)
	(layers
    (0 "F.Cu" mixed)
    (1 "In1.Cu" power)
    (2 "In2.Cu" mixed)
    (3 "In3.Cu" power)
    (4 "In4.Cu" mixed)
    (5 "In5.Cu" power)
    (6 "In6.Cu" mixed)
    (31 "B.Cu" power)
    (32 "B.Adhes" user "B.Adhesive")
    (33 "F.Adhes" user "F.Adhesive")
    (34 "B.Paste" user)
    (35 "F.Paste" user)
    (36 "B.SilkS" user "B.Silkscreen")
    (37 "F.SilkS" user "F.Silkscreen")
    (38 "B.Mask" user)
    (39 "F.Mask" user)
    (40 "Dwgs.User" user "User.Drawings")
    (41 "Cmts.User" user "User.Comments")
    (42 "Eco1.User" user "User.Eco1")
    (43 "Eco2.User" user "User.Eco2")
    (44 "Edge.Cuts" user)
    (45 "Margin" user)
    (46 "B.CrtYd" user "B.Courtyard")
    (47 "F.CrtYd" user "F.Courtyard")
    (48 "B.Fab" user)
    (49 "F.Fab" user)
  )
	(footprint "kria-k26-devboard-footprints:SOD-964" (layer "F.Cu")
    (at 167 141.9 90)
    (property "Author" "Antmicro")
    (property "License" "Apache-2.0")
    (property "MPN" "PTVS5V0Z1USKPYL")
    (property "Manufacturer" "Nexperia")
    (property "Sheetfile" "pmod.kicad_sch")
    (property "Sheetname" "PMOD")
    (property "ki_description" "Transient voltage suppressor in DSN1608-2 for mobile applications")
    (property "ki_keywords" "Transient voltage suppressor in DSN1608-2 for mobile applications")
    (attr smd)
    (fp_text reference "D2" (at -1.332967 4.472678 90) (layer "F.SilkS")
        (effects (font (size 0.7 0.7) (thickness 0.15)) (justify left bottom))
    )
    (fp_text value "PTVS5V0Z1USKP" (at 0 1.399 90) (layer "F.Fab") hide
        (effects (font (size 0.7 0.7) (thickness 0.15)) (justify left bottom))
    )
    (fp_text user "License: Apache-2.0" (at -1 5.799 90) (layer "F.Fab") hide
        (effects (font (size 0.7 0.7) (thickness 0.15)) (justify left bottom))
    )
    (fp_text user "${REFERENCE}" (at -1 3.399 90) (layer "F.Fab") hide
        (effects (font (size 0.7 0.7) (thickness 0.15)) (justify left bottom))
    )
    (fp_text user "Author: Antmicro" (at -1 4.599 90) (layer "F.Fab") hide
        (effects (font (size 0.7 0.7) (thickness 0.15)) (justify left bottom))
    )
    (fp_line (start -0.85 -0.451) (end -0.85 0.45)
      (stroke (width 0.15) (type solid)) (layer "F.SilkS"))
    (fp_line (start -0.85 -0.451) (end 0.149 -0.451)
      (stroke (width 0.15) (type solid)) (layer "F.SilkS"))
    (fp_line (start 0.149 0.45) (end -0.85 0.45)
      (stroke (width 0.15) (type solid)) (layer "F.SilkS"))
    (fp_line (start -1 -0.6) (end 0.99 -0.6)
      (stroke (width 0.05) (type solid)) (layer "F.CrtYd"))
    (fp_line (start -1 0.59) (end -1 -0.6)
      (stroke (width 0.05) (type solid)) (layer "F.CrtYd"))
    (fp_line (start 0.99 -0.6) (end 0.99 0.59)
      (stroke (width 0.05) (type solid)) (layer "F.CrtYd"))
    (fp_line (start 0.99 0.59) (end -1 0.59)
      (stroke (width 0.05) (type solid)) (layer "F.CrtYd"))
    (fp_line (start -0.651 -0.425) (end 0.65 -0.425)
      (stroke (width 0.15) (type solid)) (layer "F.Fab"))
    (fp_line (start -0.651 0.424) (end -0.651 -0.425)
      (stroke (width 0.15) (type solid)) (layer "F.Fab"))
    (fp_line (start -0.651 0.424) (end 0.65 0.424)
      (stroke (width 0.15) (type solid)) (layer "F.Fab"))
    (fp_line (start -0.451 -0.401) (end -0.451 0.4)
      (stroke (width 0.15) (type solid)) (layer "F.Fab"))
    (fp_line (start 0.65 -0.425) (end 0.65 0.424)
      (stroke (width 0.15) (type solid)) (layer "F.Fab"))
    (pad "A" smd roundrect (at 0.599 0 90) (size 0.3 0.7) (layers "F.Cu" "F.Paste" "F.Mask") (roundrect_rratio 0.25)
      (net 1 "GND") (pinfunction "A") (pintype "passive"))
    (pad "K" smd roundrect (at -0.285 0 90) (size 0.93 0.7) (layers "F.Cu" "F.Paste" "F.Mask") (roundrect_rratio 0.107)
      (net 20 "PL_3V3") (pinfunction "K") (pintype "passive"))
  )
	(footprint "kria-k26-devboard-footprints:C_0402_1005Metric" (layer "F.Cu")
    (at 133.015 136.5)
    (descr "Capacitor SMD 0402")
    (tags "capacitor SMD 0402")
    (property "Author" "Antmicro")
    (property "Dielectric" "X5R")
    (property "License" "Apache-2.0")
    (property "MPN" "GRM155R61H104KE14D")
    (property "Manufacturer" "Murata")
    (property "Sheetfile" "sd-3-card.kicad_sch")
    (property "Sheetname" "SD 3.0 card")
    (property "Val" "100n")
    (property "Voltage" "50V")
    (property "ki_description" " ")
    (attr smd)
    (fp_text reference "C14" (at -1.225 -1.57) (layer "F.SilkS")
        (effects (font (size 0.7 0.7) (thickness 0.15)) (justify left bottom))
    )
    (fp_text value "C_100n_0402" (at 0 1.4) (layer "F.Fab") hide
        (effects (font (size 0.7 0.7) (thickness 0.15)) (justify left bottom))
    )
    (fp_text user "${REFERENCE}" (at -0.932 3.168) (layer "F.Fab") hide
        (effects (font (size 0.7 0.7) (thickness 0.15)) (justify left bottom))
    )
    (fp_text user "License: Apache-2.0" (at -0.932 5.17) (layer "F.Fab") hide
        (effects (font (size 0.7 0.7) (thickness 0.15)) (justify left bottom))
    )
    (fp_text user "Author: Antmicro" (at -0.932 4.17) (layer "F.Fab") hide
        (effects (font (size 0.7 0.7) (thickness 0.15)) (justify left bottom))
    )
    (fp_rect (start -0.9659 -0.481258) (end 0.9649 0.458742)
      (stroke (width 0.05) (type solid)) (fill none) (layer "F.CrtYd"))
    (fp_line (start -0.499 -0.25) (end 0.499 -0.25)
      (stroke (width 0.15) (type solid)) (layer "F.Fab"))
    (fp_line (start -0.499 0.248) (end -0.499 -0.25)
      (stroke (width 0.15) (type solid)) (layer "F.Fab"))
    (fp_line (start 0.499 -0.25) (end 0.499 0.248)
      (stroke (width 0.15) (type solid)) (layer "F.Fab"))
    (fp_line (start 0.499 0.248) (end -0.499 0.248)
      (stroke (width 0.15) (type solid)) (layer "F.Fab"))
    (pad "1" smd roundrect (at -0.484 0) (size 0.59 0.64) (layers "F.Cu" "F.Paste" "F.Mask") (roundrect_rratio 0.25)
      (net 17 "PS_1V8") (pintype "passive"))
    (pad "2" smd roundrect (at 0.484 0) (size 0.59 0.64) (layers "F.Cu" "F.Paste" "F.Mask") (roundrect_rratio 0.25)
      (net 1 "GND") (pintype "passive"))
  )
	(footprint "kria-k26-devboard-footprints:C_0402_1005Metric" (layer "F.Cu")
    (at 133.005 137.5)
    (descr "Capacitor SMD 0402")
    (tags "capacitor SMD 0402")
    (property "Author" "Antmicro")
    (property "Dielectric" "X5R")
    (property "License" "Apache-2.0")
    (property "MPN" "GRM155R61H104KE14D")
    (property "Manufacturer" "Murata")
    (property "Sheetfile" "sd-3-card.kicad_sch")
    (property "Sheetname" "SD 3.0 card")
    (property "Val" "100n")
    (property "Voltage" "50V")
    (property "ki_description" " ")
    (attr smd)
    (fp_text reference "C16" (at -1.225 -1.57) (layer "F.SilkS")
        (effects (font (size 0.7 0.7) (thickness 0.15)) (justify left bottom))
    )
    (fp_text value "C_100n_0402" (at 0 1.4) (layer "F.Fab") hide
        (effects (font (size 0.7 0.7) (thickness 0.15)) (justify left bottom))
    )
    (fp_text user "License: Apache-2.0" (at -0.932 5.17) (layer "F.Fab") hide
        (effects (font (size 0.7 0.7) (thickness 0.15)) (justify left bottom))
    )
    (fp_text user "${REFERENCE}" (at -0.932 3.168) (layer "F.Fab") hide
        (effects (font (size 0.7 0.7) (thickness 0.15)) (justify left bottom))
    )
    (fp_text user "Author: Antmicro" (at -0.932 4.17) (layer "F.Fab") hide
        (effects (font (size 0.7 0.7) (thickness 0.15)) (justify left bottom))
    )
    (fp_rect (start -0.94 -0.47) (end 0.94 0.47)
      (stroke (width 0.05) (type solid)) (fill none) (layer "F.CrtYd"))
    (fp_rect (start -0.499 -0.249) (end 0.499 0.249)
      (stroke (width 0.15) (type solid)) (fill none) (layer "F.Fab"))
    (pad "1" smd roundrect (at -0.484 0) (size 0.59 0.64) (layers "F.Cu" "F.Paste" "F.Mask") (roundrect_rratio 0.25)
      (net 104 "/SD 3.0 card/VCCB") (pintype "passive"))
    (pad "2" smd roundrect (at 0.484 0) (size 0.59 0.64) (layers "F.Cu" "F.Paste" "F.Mask") (roundrect_rratio 0.25)
      (net 1 "GND") (pintype "passive"))
  )
	(footprint "kria-k26-devboard-footprints:C_0402_1005Metric" (layer "F.Cu")
    (at 110.91 95.98 -90)
    (descr "Capacitor SMD 0402")
    (tags "capacitor SMD 0402")
    (property "Author" "Antmicro")
    (property "Dielectric" "X5R")
    (property "License" "Apache-2.0")
    (property "MPN" "GRM155R61H104KE14D")
    (property "Manufacturer" "Murata")
    (property "Sheetfile" "clock.kicad_sch")
    (property "Sheetname" "Clock distribution")
    (property "Val" "100n")
    (property "Voltage" "50V")
    (property "ki_description" " ")
    (attr smd)
    (fp_text reference "C22" (at -0.83 -0.35 -90) (layer "F.SilkS")
        (effects (font (size 0.7 0.7) (thickness 0.15)) (justify left bottom))
    )
    (fp_text value "C_100n_0402" (at 0 1.4 -90) (layer "F.Fab") hide
        (effects (font (size 0.7 0.7) (thickness 0.15)) (justify left bottom))
    )
    (fp_text user "Author: Antmicro" (at -0.932 4.17 -90) (layer "F.Fab") hide
        (effects (font (size 0.7 0.7) (thickness 0.15)) (justify left bottom))
    )
    (fp_text user "License: Apache-2.0" (at -0.932 5.17 -90) (layer "F.Fab") hide
        (effects (font (size 0.7 0.7) (thickness 0.15)) (justify left bottom))
    )
    (fp_text user "${REFERENCE}" (at -0.932 3.168 -90) (layer "F.Fab") hide
        (effects (font (size 0.7 0.7) (thickness 0.15)) (justify left bottom))
    )
    (fp_rect (start -0.94 -0.47) (end 0.94 0.47)
      (stroke (width 0.05) (type solid)) (fill none) (layer "F.CrtYd"))
    (fp_rect (start -0.499 -0.249) (end 0.499 0.249)
      (stroke (width 0.15) (type solid)) (fill none) (layer "F.Fab"))
    (pad "1" smd roundrect (at -0.484 0 270) (size 0.59 0.64) (layers "F.Cu" "F.Paste" "F.Mask") (roundrect_rratio 0.25)
      (net 15 "PS_3V3") (pintype "passive"))
    (pad "2" smd roundrect (at 0.484 0 270) (size 0.59 0.64) (layers "F.Cu" "F.Paste" "F.Mask") (roundrect_rratio 0.25)
      (net 1 "GND") (pintype "passive"))
  )
	(footprint "kria-k26-devboard-footprints:C_0402_1005Metric" (layer "F.Cu")
    (at 112.12 96.98 90)
    (descr "Capacitor SMD 0402")
    (tags "capacitor SMD 0402")
    (property "Author" "Antmicro")
    (property "Dielectric" "X5R")
    (property "License" "Apache-2.0")
    (property "MPN" "GRM155R61H104KE14D")
    (property "Manufacturer" "Murata")
    (property "Sheetfile" "clock.kicad_sch")
    (property "Sheetname" "Clock distribution")
    (property "Val" "100n")
    (property "Voltage" "50V")
    (property "ki_description" " ")
    (attr smd)
    (fp_text reference "C25" (at 0.93 0.36 90) (layer "F.SilkS")
        (effects (font (size 0.7 0.7) (thickness 0.15)) (justify left bottom))
    )
    (fp_text value "C_100n_0402" (at 0 1.4 90) (layer "F.Fab") hide
        (effects (font (size 0.7 0.7) (thickness 0.15)) (justify left bottom))
    )
    (fp_text user "License: Apache-2.0" (at -0.932 5.17 90) (layer "F.Fab") hide
        (effects (font (size 0.7 0.7) (thickness 0.15)) (justify left bottom))
    )
    (fp_text user "Author: Antmicro" (at -0.932 4.17 90) (layer "F.Fab") hide
        (effects (font (size 0.7 0.7) (thickness 0.15)) (justify left bottom))
    )
    (fp_text user "${REFERENCE}" (at -0.932 3.168 90) (layer "F.Fab") hide
        (effects (font (size 0.7 0.7) (thickness 0.15)) (justify left bottom))
    )
    (fp_rect (start -0.94 -0.47) (end 0.94 0.47)
      (stroke (width 0.05) (type solid)) (fill none) (layer "F.CrtYd"))
    (fp_rect (start -0.499 -0.249) (end 0.499 0.249)
      (stroke (width 0.15) (type solid)) (fill none) (layer "F.Fab"))
    (pad "1" smd roundrect (at -0.484 0 90) (size 0.59 0.64) (layers "F.Cu" "F.Paste" "F.Mask") (roundrect_rratio 0.25)
      (net 15 "PS_3V3") (pintype "passive"))
    (pad "2" smd roundrect (at 0.484 0 90) (size 0.59 0.64) (layers "F.Cu" "F.Paste" "F.Mask") (roundrect_rratio 0.25)
      (net 1 "GND") (pintype "passive"))
  )
	(footprint "kria-k26-devboard-footprints:C_0402_1005Metric" (layer "F.Cu")
    (at 190.7 66.1 -90)
    (descr "Capacitor SMD 0402")
    (tags "capacitor SMD 0402")
    (property "Author" "Antmicro")
    (property "Dielectric" "X5R")
    (property "License" "Apache-2.0")
    (property "MPN" "GRM155R61H104KE14D")
    (property "Manufacturer" "Murata")
    (property "Sheetfile" "supply-oring.kicad_sch")
    (property "Sheetname" "Supply ORing")
    (property "Val" "100n")
    (property "Voltage" "50V")
    (property "ki_description" " ")
    (attr smd)
    (fp_text reference "C227" (at 1.37 -1.15 -90) (layer "F.SilkS")
        (effects (font (size 0.7 0.7) (thickness 0.15)) (justify left bottom))
    )
    (fp_text value "C_100n_0402" (at 0 1.4 -90) (layer "F.Fab") hide
        (effects (font (size 0.7 0.7) (thickness 0.15)) (justify left bottom))
    )
    (fp_text user "License: Apache-2.0" (at -0.932 5.17 -90) (layer "F.Fab") hide
        (effects (font (size 0.7 0.7) (thickness 0.15)) (justify left bottom))
    )
    (fp_text user "Author: Antmicro" (at -0.932 4.17 -90) (layer "F.Fab") hide
        (effects (font (size 0.7 0.7) (thickness 0.15)) (justify left bottom))
    )
    (fp_text user "${REFERENCE}" (at -0.932 3.168 -90) (layer "F.Fab") hide
        (effects (font (size 0.7 0.7) (thickness 0.15)) (justify left bottom))
    )
    (fp_rect (start -0.94 -0.47) (end 0.94 0.47)
      (stroke (width 0.05) (type solid)) (fill none) (layer "F.CrtYd"))
    (fp_rect (start -0.499 -0.249) (end 0.499 0.249)
      (stroke (width 0.15) (type solid)) (fill none) (layer "F.Fab"))
    (pad "1" smd roundrect (at -0.484 0 270) (size 0.59 0.64) (layers "F.Cu" "F.Paste" "F.Mask") (roundrect_rratio 0.25)
      (net 328 "Net-(U58-VDD)") (pintype "passive"))
    (pad "2" smd roundrect (at 0.484 0 270) (size 0.59 0.64) (layers "F.Cu" "F.Paste" "F.Mask") (roundrect_rratio 0.25)
      (net 331 "Net-(U58-GND)") (pintype "passive"))
  )
	(footprint "kria-k26-devboard-footprints:C_0402_1005Metric" (layer "F.Cu")
    (at 135.145 136.4 90)
    (descr "Capacitor SMD 0402")
    (tags "capacitor SMD 0402")
    (property "Author" "Antmicro")
    (property "Dielectric" "X5R")
    (property "License" "Apache-2.0")
    (property "MPN" "GRM155R61H104KE14D")
    (property "Manufacturer" "Murata")
    (property "Sheetfile" "sd-3-card.kicad_sch")
    (property "Sheetname" "SD 3.0 card")
    (property "Val" "100n")
    (property "Voltage" "50V")
    (property "ki_description" " ")
    (attr smd)
    (fp_text reference "C12" (at 0.86 0.345 90) (layer "F.SilkS")
        (effects (font (size 0.7 0.7) (thickness 0.15)) (justify left bottom))
    )
    (fp_text value "C_100n_0402" (at 0 1.4 90) (layer "F.Fab") hide
        (effects (font (size 0.7 0.7) (thickness 0.15)) (justify left bottom))
    )
    (fp_text user "${REFERENCE}" (at -0.932 3.168 90) (layer "F.Fab") hide
        (effects (font (size 0.7 0.7) (thickness 0.15)) (justify left bottom))
    )
    (fp_text user "License: Apache-2.0" (at -0.932 5.17 90) (layer "F.Fab") hide
        (effects (font (size 0.7 0.7) (thickness 0.15)) (justify left bottom))
    )
    (fp_text user "Author: Antmicro" (at -0.932 4.17 90) (layer "F.Fab") hide
        (effects (font (size 0.7 0.7) (thickness 0.15)) (justify left bottom))
    )
    (fp_rect (start -0.94 -0.47) (end 0.94 0.47)
      (stroke (width 0.05) (type solid)) (fill none) (layer "F.CrtYd"))
    (fp_rect (start -0.499 -0.249) (end 0.499 0.249)
      (stroke (width 0.15) (type solid)) (fill none) (layer "F.Fab"))
    (pad "1" smd roundrect (at -0.484 0 90) (size 0.59 0.64) (layers "F.Cu" "F.Paste" "F.Mask") (roundrect_rratio 0.25)
      (net 15 "PS_3V3") (pintype "passive"))
    (pad "2" smd roundrect (at 0.484 0 90) (size 0.59 0.64) (layers "F.Cu" "F.Paste" "F.Mask") (roundrect_rratio 0.25)
      (net 1 "GND") (pintype "passive"))
  )
	(footprint "kria-k26-devboard-footprints:C_0402_1005Metric" (layer "F.Cu")
    (at 137.7 138)
    (descr "Capacitor SMD 0402")
    (tags "capacitor SMD 0402")
    (property "Author" "Antmicro")
    (property "Dielectric" "X5R")
    (property "License" "Apache-2.0")
    (property "MPN" "GRM155R61H104KE14D")
    (property "Manufacturer" "Murata")
    (property "Sheetfile" "sd-3-card.kicad_sch")
    (property "Sheetname" "SD 3.0 card")
    (property "Val" "100n")
    (property "Voltage" "50V")
    (property "ki_description" " ")
    (attr smd)
    (fp_text reference "C15" (at -0.74 1.16) (layer "F.SilkS")
        (effects (font (size 0.7 0.7) (thickness 0.15)) (justify left bottom))
    )
    (fp_text value "C_100n_0402" (at 0 1.4) (layer "F.Fab") hide
        (effects (font (size 0.7 0.7) (thickness 0.15)) (justify left bottom))
    )
    (fp_text user "Author: Antmicro" (at -0.932 4.17) (layer "F.Fab") hide
        (effects (font (size 0.7 0.7) (thickness 0.15)) (justify left bottom))
    )
    (fp_text user "${REFERENCE}" (at -0.932 3.168) (layer "F.Fab") hide
        (effects (font (size 0.7 0.7) (thickness 0.15)) (justify left bottom))
    )
    (fp_text user "License: Apache-2.0" (at -0.932 5.17) (layer "F.Fab") hide
        (effects (font (size 0.7 0.7) (thickness 0.15)) (justify left bottom))
    )
    (fp_rect (start -0.94 -0.47) (end 0.94 0.47)
      (stroke (width 0.05) (type solid)) (fill none) (layer "F.CrtYd"))
    (fp_rect (start -0.499 -0.249) (end 0.499 0.249)
      (stroke (width 0.15) (type solid)) (fill none) (layer "F.Fab"))
    (pad "1" smd roundrect (at -0.484 0) (size 0.59 0.64) (layers "F.Cu" "F.Paste" "F.Mask") (roundrect_rratio 0.25)
      (net 104 "/SD 3.0 card/VCCB") (pintype "passive"))
    (pad "2" smd roundrect (at 0.484 0) (size 0.59 0.64) (layers "F.Cu" "F.Paste" "F.Mask") (roundrect_rratio 0.25)
      (net 1 "GND") (pintype "passive"))
  )
	(footprint "kria-k26-devboard-footprints:C_0402_1005Metric" (layer "F.Cu")
    (at 143.215 108.3 180)
    (descr "Capacitor SMD 0402")
    (tags "capacitor SMD 0402")
    (property "Author" "Antmicro")
    (property "Dielectric" "X5R")
    (property "License" "Apache-2.0")
    (property "MPN" "GRM155R61H104KE14D")
    (property "Manufacturer" "Murata")
    (property "Sheetfile" "debug.kicad_sch")
    (property "Sheetname" "Debug and JTAG")
    (property "Val" "100n")
    (property "Voltage" "50V")
    (property "ki_description" " ")
    (attr smd)
    (fp_text reference "C160" (at 1.745 1.48 180) (layer "F.SilkS")
        (effects (font (size 0.7 0.7) (thickness 0.15)) (justify left bottom))
    )
    (fp_text value "C_100n_0402" (at 0 1.4 180) (layer "F.Fab") hide
        (effects (font (size 0.7 0.7) (thickness 0.15)) (justify left bottom))
    )
    (fp_text user "License: Apache-2.0" (at -0.932 5.17 180) (layer "F.Fab") hide
        (effects (font (size 0.7 0.7) (thickness 0.15)) (justify left bottom))
    )
    (fp_text user "${REFERENCE}" (at -0.932 3.168 180) (layer "F.Fab") hide
        (effects (font (size 0.7 0.7) (thickness 0.15)) (justify left bottom))
    )
    (fp_text user "Author: Antmicro" (at -0.932 4.17 180) (layer "F.Fab") hide
        (effects (font (size 0.7 0.7) (thickness 0.15)) (justify left bottom))
    )
    (fp_rect (start -0.94 -0.47) (end 0.94 0.47)
      (stroke (width 0.05) (type solid)) (fill none) (layer "F.CrtYd"))
    (fp_rect (start -0.499 -0.249) (end 0.499 0.249)
      (stroke (width 0.15) (type solid)) (fill none) (layer "F.Fab"))
    (pad "1" smd roundrect (at -0.484 0 180) (size 0.59 0.64) (layers "F.Cu" "F.Paste" "F.Mask") (roundrect_rratio 0.25)
      (net 136 "/Debug and JTAG/PD1_SVBUS") (pintype "passive"))
    (pad "2" smd roundrect (at 0.484 0 180) (size 0.59 0.64) (layers "F.Cu" "F.Paste" "F.Mask") (roundrect_rratio 0.25)
      (net 1 "GND") (pintype "passive"))
  )
	(footprint "kria-k26-devboard-footprints:C_0402_1005Metric" (layer "F.Cu")
    (at 165.907322 141.878033 90)
    (descr "Capacitor SMD 0402")
    (tags "capacitor SMD 0402")
    (property "Author" "Antmicro")
    (property "Dielectric" "")
    (property "License" "Apache-2.0")
    (property "MPN" "C1005X6S1A105K050BC")
    (property "Manufacturer" "TDK")
    (property "Sheetfile" "pmod.kicad_sch")
    (property "Sheetname" "PMOD")
    (property "Val" "1u")
    (property "Voltage" "")
    (property "ki_description" " ")
    (attr smd)
    (fp_text reference "C36" (at -1.331967 4.522678 90) (layer "F.SilkS")
        (effects (font (size 0.7 0.7) (thickness 0.15)) (justify left bottom))
    )
    (fp_text value "C_1u_0402" (at 0 1.4 90) (layer "F.Fab") hide
        (effects (font (size 0.7 0.7) (thickness 0.15)) (justify left bottom))
    )
    (fp_text user "License: Apache-2.0" (at -0.932 5.17 90) (layer "F.Fab") hide
        (effects (font (size 0.7 0.7) (thickness 0.15)) (justify left bottom))
    )
    (fp_text user "${REFERENCE}" (at -0.932 3.168 90) (layer "F.Fab") hide
        (effects (font (size 0.7 0.7) (thickness 0.15)) (justify left bottom))
    )
    (fp_text user "Author: Antmicro" (at -0.932 4.17 90) (layer "F.Fab") hide
        (effects (font (size 0.7 0.7) (thickness 0.15)) (justify left bottom))
    )
    (fp_rect (start -0.94 -0.47) (end 0.94 0.47)
      (stroke (width 0.05) (type solid)) (fill none) (layer "F.CrtYd"))
    (fp_rect (start -0.499 -0.249) (end 0.499 0.249)
      (stroke (width 0.15) (type solid)) (fill none) (layer "F.Fab"))
    (pad "1" smd roundrect (at -0.484 0 90) (size 0.59 0.64) (layers "F.Cu" "F.Paste" "F.Mask") (roundrect_rratio 0.25)
      (net 20 "PL_3V3") (pintype "passive"))
    (pad "2" smd roundrect (at 0.484 0 90) (size 0.59 0.64) (layers "F.Cu" "F.Paste" "F.Mask") (roundrect_rratio 0.25)
      (net 1 "GND") (pintype "passive"))
  )
)
